# Bryce Canyon_IOM_IOC_Stackup.xlsx — PCB Test Plan_HVM(90+) (pcb-stackup)
|  | Board vendor give feedback of quantity in yellow columns based on the AQL table or description. |  |  |  |  |  |  |  |  |  |  |  |  |  |  |
|  | Wiwynn PM give feedback in blue columns |  |  |  |  |  |  |  |  |  |  |  |  |  |  |
| Person to be informed : PCB vendor, EE, SI, PM, PSM, Buyer, SQM |  |  |  |  |  |  |  |  |  |  |  |  |  |  |  |
| Simple flow : SI (test requirements) -> PM/AM (Total PCBS demand) -> Buyer -> Board Vendor (yellow column feedback) -> Buyer -> Person to be informed (Check and Track) |  |  |  |  |  |  |  |  |  |  |  |  |  |  |  |
| PO(purchase order) : If there are many POs for this PCB, 1st sample quantity is based on 1st PO, 2nd sample quantity is based on 2nd PO. |  |  |  |  |  |  |  |  |  |  |  |  |  |  |  |
| Project Name | PCB name | PCB# (1XXXX-XX) | Product Stage | Batch# | PCB Vendor | Production  Lot size | PCBs Demand | Delta-L Coupon (PCB Vendor) | Delta-L Coupon (3rd Party Lab) | Impedance Coupon (PCB Vendor) | In-board trace correlation (PCB Vendor) | X-section Analysis (PCB Vendor) | IST (3rd Party Lab) | IPC-6012D (3rd Party Lab) | Note |
| Bryce Canyon | FDPB | 16315-1 | HVM(90+ days) | N/A |  |  | TBD | Yes | No | Yes | No | No | No | No | Need Test? (Yes, No) |
| Tracking Code On Both Of Coupon And PCB |  |  |  |  |  |  |  | N/A |  | N/A |  |  |  |  |  |
| Test Item Acceptance Criteria |  |  |  |  |  |  |  | c = 0 |  | c = 0 |  |  |  |  |  |
| Test Item Sampling Quantity |  |  |  |  |  |  |  | 5 pcs/production lot/quarter, with max total of 30 pcs |  | Mil-STD 105E single sampling plan, AQL 0.65, level 2 |  |  |  |  |  |
| Test Time(working days) |  |  |  |  |  |  |  |  |  |  |  |  |  |  |  |
| Test Item Shipping Quantity |  |  |  |  |  |  |  |  |  |  |  |  |  |  |  |
| Shipping Address |  |  |  |  |  |  |  |  |  |  |  |  |  |  |  |
| Receiver Name |  |  |  |  |  |  |  |  |  |  |  |  |  |  |  |
| Receiver Phone# |  |  |  |  |  |  |  |  |  |  |  |  |  |  |  |
| Project Name | PCB name | PCB# (1XXXX-XX) | Product Stage | Batch# | PCB Vendor | Production  Lot size | PCBs Demand | Delta-L Coupon (PCB Vendor) | Delta-L Coupon (3rd Party Lab) | Impedance Coupon (PCB Vendor) | In-board trace correlation (PCB Vendor) | X-section Analysis (PCB Vendor) | IST (3rd Party Lab) | IPC-6012D (3rd Party Lab) | Note |
| Bryce Canyon | SCC | 16316-1 | HVM(90+ days) | N/A |  |  | TBD | No | No | Yes | No | No | No | No | Need Test? (Yes, No) |
| Tracking Code On Both Of Coupon And PCB |  |  |  |  |  |  |  |  |  | N/A |  |  |  |  |  |
| Test Item Acceptance Criteria |  |  |  |  |  |  |  |  |  | c = 0 |  |  |  |  |  |
| Test Item Sampling Quantity |  |  |  |  |  |  |  |  |  | Mil-STD 105E single sampling plan, AQL 0.65, level 2 |  |  |  |  |  |
| Test Time (working days) |  |  |  |  |  |  |  |  |  |  |  |  |  |  |  |
| Test Item Shipping Quantity |  |  |  |  |  |  |  |  |  |  |  |  |  |  |  |
| Shipping Address |  |  |  |  |  |  |  |  |  |  |  |  |  |  |  |
| Receiver Name |  |  |  |  |  |  |  |  |  |  |  |  |  |  |  |
| Receiver Phone# |  |  |  |  |  |  |  |  |  |  |  |  |  |  |  |
| Project Name | PCB name | PCB# (1XXXX-XX) | Product Stage | Batch# | PCB Vendor | Production  Lot size | PCBs Demand | Delta-L Coupon (PCB Vendor) | Delta-L Coupon (3rd Party Lab) | Impedance Coupon (PCB Vendor) | In-board trace correlation (PCB Vendor) | X-section Analysis (PCB Vendor) | IST (3rd Party Lab) | IPC-6012D (3rd Party Lab) | Note |
| Bryce Canyon | RDPB | 16317-1 | HVM(90+ days) | N/A |  |  | TBD | Yes | No | Yes | No | No | No | No | Need Test? (Yes, No) |
| Tracking Code On Both Of Coupon And PCB |  |  |  |  |  |  |  | N/A |  | N/A |  |  |  |  |  |
| Test Item Acceptance Criteria |  |  |  |  |  |  |  | c = 0 |  | c = 0 |  |  |  |  |  |
| Test Item Sampling Quantity |  |  |  |  |  |  |  | 5 pcs/production lot/quarter, with max total of 30 pcs |  | Mil-STD 105E single sampling plan, AQL 0.65, level 2 |  |  |  |  |  |
| Test Time (working days) |  |  |  |  |  |  |  |  |  |  |  |  |  |  |  |
| Test Item Shipping Quantity |  |  |  |  |  |  |  |  |  |  |  |  |  |  |  |
| Shipping Address |  |  |  |  |  |  |  |  |  |  |  |  |  |  |  |
| Receiver Name |  |  |  |  |  |  |  |  |  |  |  |  |  |  |  |
| Receiver Phone# |  |  |  |  |  |  |  |  |  |  |  |  |  |  |  |
| Project Name | PCB name | PCB# (1XXXX-XX) | Product Stage | Batch# | PCB Vendor | Production  Lot size | PCBs Demand | Delta-L Coupon (PCB Vendor) | Delta-L Coupon (3rd Party Lab) | Impedance Coupon (PCB Vendor) | In-board trace correlation (PCB Vendor) | X-section Analysis (PCB Vendor) | IST (3rd Party Lab) | IPC-6012D (3rd Party Lab) | Note |
| Bryce Canyon | IOM IOC | 16318-2 | HVM(90+ days) | N/A |  |  | TBD | No | No | Yes | No | No | No | No | Need Test? (Yes, No) |
| Tracking Code On Both Of Coupon And PCB |  |  |  |  |  |  |  |  |  | N/A |  |  |  |  |  |
| Test Item Acceptance Criteria |  |  |  |  |  |  |  |  |  | c = 0 |  |  |  |  |  |
| Test Item Sampling Quantity |  |  |  |  |  |  |  |  |  | Mil-STD 105E single sampling plan, AQL 0.65, level 2 |  |  |  |  |  |
| Test Time (working days) |  |  |  |  |  |  |  |  |  |  |  |  |  |  |  |
| Test Item Shipping Quantity |  |  |  |  |  |  |  |  |  |  |  |  |  |  |  |
| Shipping Address |  |  |  |  |  |  |  |  |  |  |  |  |  |  |  |
| Receiver Name |  |  |  |  |  |  |  |  |  |  |  |  |  |  |  |
| Receiver Phone# |  |  |  |  |  |  |  |  |  |  |  |  |  |  |  |
| Project Name | PCB name | PCB# (1XXXX-XX) | Product Stage | Batch# | PCB Vendor | Production  Lot size | PCBs Demand | Delta-L Coupon (PCB Vendor) | Delta-L Coupon (3rd Party Lab) | Impedance Coupon (PCB Vendor) | In-board trace correlation (PCB Vendor) | X-section Analysis (PCB Vendor) | IST (3rd Party Lab) | IPC-6012D (3rd Party Lab) | Note |
| Bryce Canyon | IOM M2 | 16342-2 | HVM(90+ days) | N/A |  |  | TBD | No | No | Yes | No | No | No | No | Need Test? (Yes, No) |
| Tracking Code On Both Of Coupon And PCB |  |  |  |  |  |  |  |  |  | N/A |  |  |  |  |  |
| Test Item Acceptance Criteria |  |  |  |  |  |  |  |  |  | c = 0 |  |  |  |  |  |
| Test Item Sampling Quantity |  |  |  |  |  |  |  |  |  | Mil-STD 105E single sampling plan, AQL 0.65, level 2 |  |  |  |  |  |
| Test Time (working days) |  |  |  |  |  |  |  |  |  |  |  |  |  |  |  |
| Test Item Shipping Quantity |  |  |  |  |  |  |  |  |  |  |  |  |  |  |  |
| Shipping Address |  |  |  |  |  |  |  |  |  |  |  |  |  |  |  |
| Receiver Name |  |  |  |  |  |  |  |  |  |  |  |  |  |  |  |
| Receiver Phone# |  |  |  |  |  |  |  |  |  |  |  |  |  |  |  |
